# BASEBOARD_FAB2 (Tioga Pass) — schematic netlist excerpt (pin names and nets, part order shuffled) for the footprints in the layout excerpt that follows; sources: Cadence DE-HDL packaged netlist, KiCad conversion of Wiwynn_Tioga_Pass_MB.brd

C1F28  CAP_A  0.1UF 16V 10% X7R  pkg 0402V  page 224 : A = VR_FET_SW_P12V_STBY_PVDDQ_GHJ ; B = GND
C9G6  CAP_A  0.1UF 16V 10% X7R  pkg 0402V  page 141 : A = GND_LAN_TRCT1234_C ; B = GND
R8E11  RES  0.0 5% EMPTY  pkg 0402  page 156 : A = FM_MEM_THERM_EVENT_LVT3_N ; B = FM_ADR_SMI_GPIO_N

(kicad_pcb
	(version 20260206)
	(generator "pcbnew")
	(generator_version "10.0")
	(general
		(thickness 1.6)
		(legacy_teardrops no)
	)
	(paper "A4")
	(title_block
		(title "Wiwynn_Tioga_Pass_MB.brd")
		(comment 1 "Tioga Pass / footprints 1338-1340 of 4770")
	)
	(layers
		(0 "F.Cu" signal "TOP")
		(4 "In1.Cu" signal "L2GND")
		(6 "In2.Cu" signal "L3")
		(8 "In3.Cu" signal "L4GND")
		(10 "In4.Cu" signal "L5")
		(12 "In5.Cu" signal "L6GND")
		(14 "In6.Cu" signal "L7VCC")
		(16 "In7.Cu" signal "L8VCC")
		(18 "In8.Cu" signal "L9GND")
		(20 "In9.Cu" signal "L10")
		(22 "In10.Cu" signal "L11GND")
		(24 "In11.Cu" signal "L12")
		(26 "In12.Cu" signal "L13GND")
		(2 "B.Cu" signal "BOTTOM")
		(9 "F.Adhes" user "F.Adhesive")
		(11 "B.Adhes" user "B.Adhesive")
		(13 "F.Paste" user "Package Geometry/Pastemask Top")
		(15 "B.Paste" user "Package Geometry/Pastemask Bottom")
		(5 "F.SilkS" user "Ref Des/Silkscreen Top")
		(7 "B.SilkS" user "Ref Des/Silkscreen Bottom")
		(1 "F.Mask" user "Board Geometry/Soldermask Top")
		(3 "B.Mask" user "Board Geometry/Soldermask Bottom")
		(17 "Dwgs.User" user "User.Drawings")
		(19 "Cmts.User" user "User.Comments")
		(21 "Eco1.User" user "User.Eco1")
		(23 "Eco2.User" user "User.Eco2")
		(25 "Edge.Cuts" user "Board Geometry/Outline")
		(27 "Margin" user)
		(31 "F.CrtYd" user "Package Geometry/Place Bound Top")
		(29 "B.CrtYd" user "Package Geometry/Place Bound Bottom")
		(35 "F.Fab" user "Ref Des/Assembly Top")
		(33 "B.Fab" user "Ref Des/Assembly Bottom")
	)
	(footprint ""
		(layer "F.Cu")
		(at 4.533138 -20.77339 90)
		(property "Reference" "C1F28"
			(at 0 0 90)
			(layer "F.SilkS")
			(hide yes)
			(effects
				(font
					(size 1.27 1.27)
				)
			)
		)
		(property "Value" ""
			(at 0 0 90)
			(layer "F.Fab")
			(effects
				(font
					(size 1.27 1.27)
				)
			)
		)
		(duplicate_pad_numbers_are_jumpers no)
		(fp_rect
			(start 0.3048 -0.1016)
			(end -0.3048 0.9906)
			(stroke
				(width 0)
				(type default)
			)
			(fill no)
			(layer "F.CrtYd")
		)
		(fp_line
			(start 0.3048 -0.1016)
			(end -0.3048 -0.1016)
			(stroke
				(width 0.1)
				(type default)
			)
			(layer "F.Fab")
		)
		(fp_line
			(start -0.3048 -0.1016)
			(end -0.3048 0.9906)
			(stroke
				(width 0.1)
				(type default)
			)
			(layer "F.Fab")
		)
		(fp_line
			(start 0.3048 0.9906)
			(end 0.3048 -0.1016)
			(stroke
				(width 0.1)
				(type default)
			)
			(layer "F.Fab")
		)
		(fp_line
			(start -0.3048 0.9906)
			(end 0.3048 0.9906)
			(stroke
				(width 0.1)
				(type default)
			)
			(layer "F.Fab")
		)
		(pad "1" smd rect
			(at 0 0 90)
			(size 0.508 0.508)
			(layers "F.Cu" "F.Mask" "F.Paste")
			(net "VR_FET_SW_P12V_STBY_PVDDQ_GHJ")
		)
		(pad "2" smd rect
			(at 0 0.889 90)
			(size 0.508 0.508)
			(layers "F.Cu" "F.Mask" "F.Paste")
			(net "GND")
		)
		(zone
			(layer "F.Cu")
			(hatch none 0.5)
			(connect_pads
				(clearance 0)
			)
			(min_thickness 0.25)
			(keepout
				(tracks allowed)
				(vias not_allowed)
				(pads allowed)
				(copperpour not_allowed)
				(footprints allowed)
			)
			(placement
				(enabled no)
				(sheetname "")
			)
			(fill
				(thermal_gap 0.5)
				(thermal_bridge_width 0.5)
				(island_removal_mode 0)
			)
			(polygon
				(pts
					(xy 4.787138 -21.02739) (xy 4.787138 -20.51939) (xy 5.168138 -20.51939) (xy 5.168138 -21.02739)
				)
			)
		)
		(zone
			(layer "F.Cu")
			(hatch none 0.5)
			(connect_pads
				(clearance 0)
			)
			(min_thickness 0.25)
			(keepout
				(tracks not_allowed)
				(vias allowed)
				(pads allowed)
				(copperpour not_allowed)
				(footprints allowed)
			)
			(placement
				(enabled no)
				(sheetname "")
			)
			(fill
				(thermal_gap 0.5)
				(thermal_bridge_width 0.5)
				(island_removal_mode 0)
			)
			(polygon
				(pts
					(xy 4.787138 -21.02739) (xy 4.787138 -20.51939) (xy 5.168138 -20.51939) (xy 5.168138 -21.02739)
				)
			)
		)
	)
	(footprint ""
		(layer "F.Cu")
		(at 480.08286 -18.48739)
		(property "Reference" "C9G6"
			(at 0 0 0)
			(layer "F.SilkS")
			(hide yes)
			(effects
				(font
					(size 1.27 1.27)
				)
			)
		)
		(property "Value" ""
			(at 0 0 0)
			(layer "F.Fab")
			(effects
				(font
					(size 1.27 1.27)
				)
			)
		)
		(duplicate_pad_numbers_are_jumpers no)
		(fp_poly
			(pts
				(xy 0.3048 -0.1016) (xy 0.3048 0.9906) (xy -0.3048 0.9906) (xy -0.3048 -0.1016)
			)
			(stroke
				(width 0)
				(type default)
			)
			(fill no)
			(layer "F.CrtYd")
		)
		(fp_line
			(start -0.3048 -0.1016)
			(end -0.3048 0.9906)
			(stroke
				(width 0.1)
				(type default)
			)
			(layer "F.Fab")
		)
		(fp_line
			(start -0.3048 0.9906)
			(end 0.3048 0.9906)
			(stroke
				(width 0.1)
				(type default)
			)
			(layer "F.Fab")
		)
		(fp_line
			(start 0.3048 -0.1016)
			(end -0.3048 -0.1016)
			(stroke
				(width 0.1)
				(type default)
			)
			(layer "F.Fab")
		)
		(fp_line
			(start 0.3048 0.9906)
			(end 0.3048 -0.1016)
			(stroke
				(width 0.1)
				(type default)
			)
			(layer "F.Fab")
		)
		(pad "1" smd rect
			(at 0 0)
			(size 0.508 0.508)
			(layers "F.Cu" "F.Mask" "F.Paste")
			(net "GND_LAN_TRCT1234_C")
		)
		(pad "2" smd rect
			(at 0 0.889)
			(size 0.508 0.508)
			(layers "F.Cu" "F.Mask" "F.Paste")
			(net "GND")
		)
		(zone
			(layer "F.Cu")
			(hatch none 0.5)
			(connect_pads
				(clearance 0)
			)
			(min_thickness 0.25)
			(keepout
				(tracks allowed)
				(vias not_allowed)
				(pads allowed)
				(copperpour not_allowed)
				(footprints allowed)
			)
			(placement
				(enabled no)
				(sheetname "")
			)
			(fill
				(thermal_gap 0.5)
				(thermal_bridge_width 0.5)
				(island_removal_mode 0)
			)
			(polygon
				(pts
					(xy 479.82886 -18.23339) (xy 480.33686 -18.23339) (xy 480.33686 -17.85239) (xy 479.82886 -17.85239)
				)
			)
		)
		(zone
			(layer "F.Cu")
			(hatch none 0.5)
			(connect_pads
				(clearance 0)
			)
			(min_thickness 0.25)
			(keepout
				(tracks not_allowed)
				(vias allowed)
				(pads allowed)
				(copperpour not_allowed)
				(footprints allowed)
			)
			(placement
				(enabled no)
				(sheetname "")
			)
			(fill
				(thermal_gap 0.5)
				(thermal_bridge_width 0.5)
				(island_removal_mode 0)
			)
			(polygon
				(pts
					(xy 479.82886 -17.85239) (xy 480.33686 -17.85239) (xy 480.33686 -18.23339) (xy 479.82886 -18.23339)
				)
			)
		)
	)
	(footprint ""
		(layer "F.Cu")
		(at 415.7345 -114.173 -90)
		(property "Reference" "R8E11"
			(at 0 0 270)
			(layer "F.SilkS")
			(hide yes)
			(effects
				(font
					(size 1.27 1.27)
				)
			)
		)
		(property "Value" ""
			(at 0 0 270)
			(layer "F.Fab")
			(effects
				(font
					(size 1.27 1.27)
				)
			)
		)
		(duplicate_pad_numbers_are_jumpers no)
		(fp_poly
			(pts
				(xy -0.2794 -0.1016) (xy 0.2794 -0.1016) (xy 0.2794 0.9906) (xy -0.2794 0.9906)
			)
			(stroke
				(width 0)
				(type default)
			)
			(fill no)
			(layer "F.CrtYd")
		)
		(fp_line
			(start -0.2794 0.9906)
			(end 0.2794 0.9906)
			(stroke
				(width 0.1)
				(type default)
			)
			(layer "F.Fab")
		)
		(fp_line
			(start 0.2794 0.9906)
			(end 0.2794 -0.1016)
			(stroke
				(width 0.1)
				(type default)
			)
			(layer "F.Fab")
		)
		(fp_line
			(start -0.2794 -0.1016)
			(end -0.2794 0.9906)
			(stroke
				(width 0.1)
				(type default)
			)
			(layer "F.Fab")
		)
		(fp_line
			(start 0.2794 -0.1016)
			(end -0.2794 -0.1016)
			(stroke
				(width 0.1)
				(type default)
			)
			(layer "F.Fab")
		)
		(pad "1" smd rect
			(at 0 0 270)
			(size 0.508 0.508)
			(layers "F.Cu" "F.Mask" "F.Paste")
			(net "FM_MEM_THERM_EVENT_LVT3_N")
		)
		(pad "2" smd rect
			(at 0 0.889 270)
			(size 0.508 0.508)
			(layers "F.Cu" "F.Mask" "F.Paste")
			(net "FM_ADR_SMI_GPIO_N")
		)
		(zone
			(layer "F.Cu")
			(hatch none 0.5)
			(connect_pads
				(clearance 0)
			)
			(min_thickness 0.25)
			(keepout
				(tracks not_allowed)
				(vias allowed)
				(pads allowed)
				(copperpour not_allowed)
				(footprints allowed)
			)
			(placement
				(enabled no)
				(sheetname "")
			)
			(fill
				(thermal_gap 0.5)
				(thermal_bridge_width 0.5)
				(island_removal_mode 0)
			)
			(polygon
				(pts
					(xy 415.0995 -114.427) (xy 415.0995 -113.919) (xy 415.4805 -113.919) (xy 415.4805 -114.427)
				)
			)
		)
		(zone
			(layer "F.Cu")
			(hatch none 0.5)
			(connect_pads
				(clearance 0)
			)
			(min_thickness 0.25)
			(keepout
				(tracks allowed)
				(vias not_allowed)
				(pads allowed)
				(copperpour not_allowed)
				(footprints allowed)
			)
			(placement
				(enabled no)
				(sheetname "")
			)
			(fill
				(thermal_gap 0.5)
				(thermal_bridge_width 0.5)
				(island_removal_mode 0)
			)
			(polygon
				(pts
					(xy 415.4805 -114.427) (xy 415.4805 -113.919) (xy 415.0995 -113.919) (xy 415.0995 -114.427)
				)
			)
		)
	)
)
